# T6G (Grand Teton) — schematic netlist excerpt (pin names and nets, part order shuffled) for the footprints in the layout excerpt that follows; sources: Cadence DE-HDL packaged netlist, KiCad conversion of 04192023_DAF0TMB3IC0_F0TG_MB_C_brd_V02_OCP.brd

R4134  Q_RES  100K 1% EMPTY  pkg 0402LF  page 125 : A = GPU_3V3IO_RSVD5_FFU ; B = GND
PC576  Q_CAP  22UF 16V 20% X6S  pkg C0805  page 190 : A = SW_P3V3_AUX_FLT ; B = GND
H34  HOLE  EMPTY  pkg TH  page 230 : \1\ = GND

(kicad_pcb
	(version 20260206)
	(generator "pcbnew")
	(generator_version "10.0")
	(general
		(thickness 1.6)
		(legacy_teardrops no)
	)
	(paper "A4")
	(title_block
		(title "04192023_DAF0TMB3IC0_F0TG_MB_C_brd_V02_OCP.brd")
		(comment 1 "Grand Teton / footprints 4798-4800 of 8354")
	)
	(layers
		(0 "F.Cu" signal "TOP")
		(4 "In1.Cu" signal "GND")
		(6 "In2.Cu" signal "IN1")
		(8 "In3.Cu" signal "GND1")
		(10 "In4.Cu" signal "IN2")
		(12 "In5.Cu" signal "GND2")
		(14 "In6.Cu" signal "IN3")
		(16 "In7.Cu" signal "GND3")
		(18 "In8.Cu" signal "VCC")
		(20 "In9.Cu" signal "VCC1")
		(22 "In10.Cu" signal "GND4")
		(24 "In11.Cu" signal "IN4")
		(26 "In12.Cu" signal "GND5")
		(28 "In13.Cu" signal "IN5")
		(30 "In14.Cu" signal "GND6")
		(32 "In15.Cu" signal "IN6")
		(34 "In16.Cu" signal "GND7")
		(2 "B.Cu" signal "BOTTOM")
		(9 "F.Adhes" user "F.Adhesive")
		(11 "B.Adhes" user "B.Adhesive")
		(13 "F.Paste" user "Package Geometry/Pastemask Top")
		(15 "B.Paste" user "Package Geometry/Pastemask Bottom")
		(5 "F.SilkS" user "Ref Des/Silkscreen Top")
		(7 "B.SilkS" user "Ref Des/Silkscreen Bottom")
		(1 "F.Mask" user "Board Geometry/Soldermask Top")
		(3 "B.Mask" user "Board Geometry/Soldermask Bottom")
		(17 "Dwgs.User" user "User.Drawings")
		(19 "Cmts.User" user "User.Comments")
		(21 "Eco1.User" user "User.Eco1")
		(23 "Eco2.User" user "User.Eco2")
		(25 "Edge.Cuts" user "Board Geometry/Outline")
		(27 "Margin" user)
		(31 "F.CrtYd" user "Package Geometry/Place Bound Top")
		(29 "B.CrtYd" user "Package Geometry/Place Bound Bottom")
		(35 "F.Fab" user "Ref Des/Assembly Top")
		(33 "B.Fab" user "Ref Des/Assembly Bottom")
	)
	(footprint ""
		(layer "F.Cu")
		(at 448.271392 -47.506382 -90)
		(property "Reference" "PC576"
			(at 0 0 270)
			(layer "F.SilkS")
			(hide yes)
			(effects
				(font
					(size 1.27 1.27)
				)
			)
		)
		(property "Value" ""
			(at 0 0 270)
			(layer "F.Fab")
			(effects
				(font
					(size 1.27 1.27)
				)
			)
		)
		(duplicate_pad_numbers_are_jumpers no)
		(fp_line
			(start -1.524 0.762)
			(end -1.524 -0.762)
			(stroke
				(width 0.1524)
				(type default)
			)
			(layer "F.SilkS")
		)
		(fp_line
			(start 1.524 0.762)
			(end -1.524 0.762)
			(stroke
				(width 0.1524)
				(type default)
			)
			(layer "F.SilkS")
		)
		(fp_line
			(start -1.524 -0.762)
			(end 1.524 -0.762)
			(stroke
				(width 0.1524)
				(type default)
			)
			(layer "F.SilkS")
		)
		(fp_line
			(start 1.524 -0.762)
			(end 1.524 0.762)
			(stroke
				(width 0.1524)
				(type default)
			)
			(layer "F.SilkS")
		)
		(fp_line
			(start -1.1049 0.724916)
			(end 1.1049 0.724916)
			(stroke
				(width 0.1)
				(type default)
			)
			(layer "F.Fab")
		)
		(fp_line
			(start 1.1049 0.724916)
			(end 1.1049 -0.724916)
			(stroke
				(width 0.1)
				(type default)
			)
			(layer "F.Fab")
		)
		(fp_line
			(start -1.1049 -0.724916)
			(end -1.1049 0.724916)
			(stroke
				(width 0.1)
				(type default)
			)
			(layer "F.Fab")
		)
		(fp_line
			(start 1.1049 -0.724916)
			(end -1.1049 -0.724916)
			(stroke
				(width 0.1)
				(type default)
			)
			(layer "F.Fab")
		)
		(pad "1" smd rect
			(at -0.889 0 90)
			(size 1.016 1.27)
			(layers "F.Cu" "F.Mask" "F.Paste")
			(net "SW_P3V3_AUX_FLT")
		)
		(pad "2" smd rect
			(at 0.889 0 90)
			(size 1.016 1.27)
			(layers "F.Cu" "F.Mask" "F.Paste")
			(net "GND")
		)
	)
	(footprint ""
		(layer "F.Cu")
		(at 441.951872 -351.415858)
		(property "Reference" "H34"
			(at -1.7272 -4.177792 0)
			(unlocked yes)
			(layer "F.SilkS")
			(effects
				(font
					(size 0.7874 0.5842)
					(thickness 0.1524)
				)
				(justify left)
			)
		)
		(property "Value" ""
			(at 0 0 0)
			(layer "F.Fab")
			(effects
				(font
					(size 1.27 1.27)
				)
			)
		)
		(duplicate_pad_numbers_are_jumpers no)
		(pad "1" thru_hole circle
			(at 0 0)
			(size 6.1976 6.1976)
			(drill 3.7338)
			(layers "*.Cu" "*.Mask")
			(remove_unused_layers no)
			(net "GND")
			(clearance -0.9779)
			(padstack
				(mode front_inner_back)
				(layer "Inner"
					(shape circle)
					(size 5.5372 5.5372)
					(clearance -0.6477)
				)
				(layer "B.Cu"
					(shape circle)
					(size 6.1976 6.1976)
					(clearance -0.9779)
				)
			)
		)
	)
	(footprint ""
		(layer "F.Cu")
		(at 308.420516 -437.498744 -90)
		(property "Reference" "R4134"
			(at 0 0 270)
			(layer "F.SilkS")
			(hide yes)
			(effects
				(font
					(size 1.27 1.27)
				)
			)
		)
		(property "Value" ""
			(at 0 0 270)
			(layer "F.Fab")
			(effects
				(font
					(size 1.27 1.27)
				)
			)
		)
		(duplicate_pad_numbers_are_jumpers no)
		(fp_line
			(start -0.7874 0.4064)
			(end -0.7874 -0.4064)
			(stroke
				(width 0.1524)
				(type default)
			)
			(layer "F.SilkS")
		)
		(fp_line
			(start 0.7874 0.4064)
			(end -0.7874 0.4064)
			(stroke
				(width 0.1524)
				(type default)
			)
			(layer "F.SilkS")
		)
		(fp_line
			(start -0.7874 -0.4064)
			(end 0.7874 -0.4064)
			(stroke
				(width 0.1524)
				(type default)
			)
			(layer "F.SilkS")
		)
		(fp_line
			(start 0.7874 -0.4064)
			(end 0.7874 0.4064)
			(stroke
				(width 0.1524)
				(type default)
			)
			(layer "F.SilkS")
		)
		(fp_line
			(start -0.67945 0.3048)
			(end -0.67945 -0.305054)
			(stroke
				(width 0.1)
				(type default)
			)
			(layer "F.Fab")
		)
		(fp_line
			(start -0.12065 0.3048)
			(end -0.67945 0.3048)
			(stroke
				(width 0.1)
				(type default)
			)
			(layer "F.Fab")
		)
		(fp_line
			(start 0.120396 0.3048)
			(end 0.120396 0.2794)
			(stroke
				(width 0.1)
				(type default)
			)
			(layer "F.Fab")
		)
		(fp_line
			(start 0.67945 0.3048)
			(end 0.120396 0.3048)
			(stroke
				(width 0.1)
				(type default)
			)
			(layer "F.Fab")
		)
		(fp_line
			(start -0.12065 0.2794)
			(end -0.12065 0.3048)
			(stroke
				(width 0.1)
				(type default)
			)
			(layer "F.Fab")
		)
		(fp_line
			(start 0.120396 0.2794)
			(end -0.12065 0.2794)
			(stroke
				(width 0.1)
				(type default)
			)
			(layer "F.Fab")
		)
		(fp_line
			(start -0.12065 -0.2794)
			(end 0.12065 -0.2794)
			(stroke
				(width 0.1)
				(type default)
			)
			(layer "F.Fab")
		)
		(fp_line
			(start 0.12065 -0.2794)
			(end 0.12065 -0.3048)
			(stroke
				(width 0.1)
				(type default)
			)
			(layer "F.Fab")
		)
		(fp_line
			(start 0.12065 -0.3048)
			(end 0.67945 -0.3048)
			(stroke
				(width 0.1)
				(type default)
			)
			(layer "F.Fab")
		)
		(fp_line
			(start 0.67945 -0.3048)
			(end 0.67945 0.3048)
			(stroke
				(width 0.1)
				(type default)
			)
			(layer "F.Fab")
		)
		(fp_line
			(start -0.67945 -0.305054)
			(end -0.12065 -0.305054)
			(stroke
				(width 0.1)
				(type default)
			)
			(layer "F.Fab")
		)
		(fp_line
			(start -0.12065 -0.305054)
			(end -0.12065 -0.2794)
			(stroke
				(width 0.1)
				(type default)
			)
			(layer "F.Fab")
		)
		(pad "1" smd circle
			(at -0.40005 0 270)
			(size 0 0)
			(layers "F.Cu" "F.Mask" "F.Paste")
			(net "GPU_3V3IO_RSVD5_FFU")
		)
		(pad "2" smd circle
			(at 0.40005 0 270)
			(size 0 0)
			(layers "F.Cu" "F.Mask" "F.Paste")
			(net "GND")
		)
	)
)
